(kicad_pcb
	(version 20260206)
	(generator "pcbnew")
	(generator_version "10.0")
	(general
		(thickness 1.6)
		(legacy_teardrops no)
	)
	(paper "A4")
	(title_block
		(title "04192023_DAF0TMB3IC0_F0TG_MB_C_brd_V02_OCP.brd")
		(comment 1 "Grand Teton / footprints 6281-6287 of 8354")
	)
	(layers
		(0 "F.Cu" signal "TOP")
		(4 "In1.Cu" signal "GND")
		(6 "In2.Cu" signal "IN1")
		(8 "In3.Cu" signal "GND1")
		(10 "In4.Cu" signal "IN2")
		(12 "In5.Cu" signal "GND2")
		(14 "In6.Cu" signal "IN3")
		(16 "In7.Cu" signal "GND3")
		(18 "In8.Cu" signal "VCC")
		(20 "In9.Cu" signal "VCC1")
		(22 "In10.Cu" signal "GND4")
		(24 "In11.Cu" signal "IN4")
		(26 "In12.Cu" signal "GND5")
		(28 "In13.Cu" signal "IN5")
		(30 "In14.Cu" signal "GND6")
		(32 "In15.Cu" signal "IN6")
		(34 "In16.Cu" signal "GND7")
		(2 "B.Cu" signal "BOTTOM")
		(9 "F.Adhes" user "F.Adhesive")
		(11 "B.Adhes" user "B.Adhesive")
		(13 "F.Paste" user "Package Geometry/Pastemask Top")
		(15 "B.Paste" user "Package Geometry/Pastemask Bottom")
		(5 "F.SilkS" user "Ref Des/Silkscreen Top")
		(7 "B.SilkS" user "Ref Des/Silkscreen Bottom")
		(1 "F.Mask" user "Board Geometry/Soldermask Top")
		(3 "B.Mask" user "Board Geometry/Soldermask Bottom")
		(17 "Dwgs.User" user "User.Drawings")
		(19 "Cmts.User" user "User.Comments")
		(21 "Eco1.User" user "User.Eco1")
		(23 "Eco2.User" user "User.Eco2")
		(25 "Edge.Cuts" user "Board Geometry/Outline")
		(27 "Margin" user)
		(31 "F.CrtYd" user "Package Geometry/Place Bound Top")
		(29 "B.CrtYd" user "Package Geometry/Place Bound Bottom")
		(35 "F.Fab" user "Ref Des/Assembly Top")
		(33 "B.Fab" user "Ref Des/Assembly Bottom")
	)
	(footprint ""
		(layer "B.Cu")
		(at 352.24466 -333.121 -90)
		(property "Reference" "PC100"
			(at 9.640316 0.988314 270)
			(unlocked yes)
			(layer "B.SilkS")
			(effects
				(font
					(size 0.7874 0.5842)
					(thickness 0.1524)
				)
				(justify left mirror)
			)
		)
		(property "Value" ""
			(at 0 0 90)
			(layer "B.Fab")
			(effects
				(font
					(size 1.27 1.27)
				)
				(justify mirror)
			)
		)
		(duplicate_pad_numbers_are_jumpers no)
		(fp_line
			(start -4.533392 2.249932)
			(end 4.533392 2.249932)
			(stroke
				(width 0.1524)
				(type default)
			)
			(layer "B.SilkS")
		)
		(fp_line
			(start 4.533392 2.249932)
			(end 4.533392 -2.249932)
			(stroke
				(width 0.1524)
				(type default)
			)
			(layer "B.SilkS")
		)
		(fp_line
			(start -4.533392 -2.249932)
			(end -4.533392 2.249932)
			(stroke
				(width 0.1524)
				(type default)
			)
			(layer "B.SilkS")
		)
		(fp_line
			(start 4.533392 -2.249932)
			(end -4.533392 -2.249932)
			(stroke
				(width 0.1524)
				(type default)
			)
			(layer "B.SilkS")
		)
		(fp_rect
			(start 5.39242 2.326132)
			(end 4.533392 -2.326132)
			(stroke
				(width 0)
				(type default)
			)
			(fill yes)
			(layer "B.SilkS")
		)
		(fp_line
			(start -3.750056 2.249932)
			(end 3.750056 2.249932)
			(stroke
				(width 0.1)
				(type default)
			)
			(layer "B.Fab")
		)
		(fp_line
			(start 3.750056 2.249932)
			(end 3.750056 -2.249932)
			(stroke
				(width 0.1)
				(type default)
			)
			(layer "B.Fab")
		)
		(fp_line
			(start -3.750056 -2.249932)
			(end -3.750056 2.249932)
			(stroke
				(width 0.1)
				(type default)
			)
			(layer "B.Fab")
		)
		(fp_line
			(start 3.750056 -2.249932)
			(end -3.750056 -2.249932)
			(stroke
				(width 0.1)
				(type default)
			)
			(layer "B.Fab")
		)
		(fp_text user "-"
			(at -4.36499 2.896108 270)
			(unlocked yes)
			(layer "B.SilkS")
			(effects
				(font
					(size 1.905 1.4224)
					(thickness 0.1524)
				)
				(justify left mirror)
			)
		)
		(fp_text user "+"
			(at 6.322314 0.786384 180)
			(unlocked yes)
			(layer "B.SilkS")
			(effects
				(font
					(size 1.905 1.4224)
					(thickness 0.1524)
				)
				(justify left mirror)
			)
		)
		(fp_text user "+"
			(at 6.322314 0.786384 180)
			(unlocked yes)
			(layer "B.Fab")
			(effects
				(font
					(size 1.905 1.4224)
					(thickness 0.1524)
				)
				(justify left mirror)
			)
		)
		(fp_text user "-"
			(at -4.8514 -0.14605 270)
			(unlocked yes)
			(layer "B.Fab")
			(effects
				(font
					(size 1.905 1.4224)
					(thickness 0.1524)
				)
				(justify left mirror)
			)
		)
		(pad "1" smd rect
			(at 3.199892 0 90)
			(size 2.413 2.8194)
			(layers "B.Cu" "B.Mask" "B.Paste")
			(net "PVDDCR_CPU1_P0")
		)
		(pad "2" smd rect
			(at -3.199892 0 90)
			(size 2.413 2.8194)
			(layers "B.Cu" "B.Mask" "B.Paste")
			(net "GND")
		)
	)
	(footprint ""
		(layer "B.Cu")
		(at 296.479722 -193.99631)
		(property "Reference" "R90"
			(at 0 0 0)
			(layer "B.SilkS")
			(hide yes)
			(effects
				(font
					(size 1.27 1.27)
				)
				(justify mirror)
			)
		)
		(property "Value" ""
			(at 0 0 0)
			(layer "B.Fab")
			(effects
				(font
					(size 1.27 1.27)
				)
				(justify mirror)
			)
		)
		(duplicate_pad_numbers_are_jumpers no)
		(fp_line
			(start -0.7874 -0.4064)
			(end -0.7874 0.4064)
			(stroke
				(width 0.1524)
				(type default)
			)
			(layer "B.SilkS")
		)
		(fp_line
			(start -0.7874 0.4064)
			(end 0.7874 0.4064)
			(stroke
				(width 0.1524)
				(type default)
			)
			(layer "B.SilkS")
		)
		(fp_line
			(start 0.7874 -0.4064)
			(end -0.7874 -0.4064)
			(stroke
				(width 0.1524)
				(type default)
			)
			(layer "B.SilkS")
		)
		(fp_line
			(start 0.7874 0.4064)
			(end 0.7874 -0.4064)
			(stroke
				(width 0.1524)
				(type default)
			)
			(layer "B.SilkS")
		)
		(fp_line
			(start -0.67945 -0.3048)
			(end -0.67945 0.3048)
			(stroke
				(width 0.1)
				(type default)
			)
			(layer "B.Fab")
		)
		(fp_line
			(start -0.67945 0.3048)
			(end -0.120396 0.3048)
			(stroke
				(width 0.1)
				(type default)
			)
			(layer "B.Fab")
		)
		(fp_line
			(start -0.12065 -0.3048)
			(end -0.67945 -0.3048)
			(stroke
				(width 0.1)
				(type default)
			)
			(layer "B.Fab")
		)
		(fp_line
			(start -0.12065 -0.2794)
			(end -0.12065 -0.3048)
			(stroke
				(width 0.1)
				(type default)
			)
			(layer "B.Fab")
		)
		(fp_line
			(start -0.120396 0.2794)
			(end 0.12065 0.2794)
			(stroke
				(width 0.1)
				(type default)
			)
			(layer "B.Fab")
		)
		(fp_line
			(start -0.120396 0.3048)
			(end -0.120396 0.2794)
			(stroke
				(width 0.1)
				(type default)
			)
			(layer "B.Fab")
		)
		(fp_line
			(start 0.12065 -0.305054)
			(end 0.12065 -0.2794)
			(stroke
				(width 0.1)
				(type default)
			)
			(layer "B.Fab")
		)
		(fp_line
			(start 0.12065 -0.2794)
			(end -0.12065 -0.2794)
			(stroke
				(width 0.1)
				(type default)
			)
			(layer "B.Fab")
		)
		(fp_line
			(start 0.12065 0.2794)
			(end 0.12065 0.3048)
			(stroke
				(width 0.1)
				(type default)
			)
			(layer "B.Fab")
		)
		(fp_line
			(start 0.12065 0.3048)
			(end 0.67945 0.3048)
			(stroke
				(width 0.1)
				(type default)
			)
			(layer "B.Fab")
		)
		(fp_line
			(start 0.67945 -0.305054)
			(end 0.12065 -0.305054)
			(stroke
				(width 0.1)
				(type default)
			)
			(layer "B.Fab")
		)
		(fp_line
			(start 0.67945 0.3048)
			(end 0.67945 -0.305054)
			(stroke
				(width 0.1)
				(type default)
			)
			(layer "B.Fab")
		)
		(pad "1" smd circle
			(at 0.40005 0 180)
			(size 0 0)
			(layers "B.Cu" "B.Mask" "B.Paste")
			(net "P3V3")
		)
		(pad "2" smd circle
			(at -0.40005 0 180)
			(size 0 0)
			(layers "B.Cu" "B.Mask" "B.Paste")
			(net "PWRGD_CHB_CPU0_DIMM")
		)
	)
	(footprint ""
		(layer "B.Cu")
		(at 133.683756 -386.766562 90)
		(property "Reference" "C485"
			(at 0 0 90)
			(layer "B.SilkS")
			(hide yes)
			(effects
				(font
					(size 1.27 1.27)
				)
				(justify mirror)
			)
		)
		(property "Value" ""
			(at 0 0 90)
			(layer "B.Fab")
			(effects
				(font
					(size 1.27 1.27)
				)
				(justify mirror)
			)
		)
		(duplicate_pad_numbers_are_jumpers no)
		(fp_line
			(start 0.299974 -0.150114)
			(end -0.299974 -0.150114)
			(stroke
				(width 0.1)
				(type default)
			)
			(layer "B.Fab")
		)
		(fp_line
			(start -0.299974 -0.150114)
			(end -0.299974 0.150114)
			(stroke
				(width 0.1)
				(type default)
			)
			(layer "B.Fab")
		)
		(fp_line
			(start 0.299974 0.150114)
			(end 0.299974 -0.150114)
			(stroke
				(width 0.1)
				(type default)
			)
			(layer "B.Fab")
		)
		(fp_line
			(start -0.299974 0.150114)
			(end 0.299974 0.150114)
			(stroke
				(width 0.1)
				(type default)
			)
			(layer "B.Fab")
		)
		(pad "1" smd rect
			(at 0.2667 0 270)
			(size 0.3048 0.381)
			(layers "B.Cu" "B.Mask" "B.Paste")
			(net "P0V9_CPU1_RT3_2A")
		)
		(pad "2" smd rect
			(at -0.2667 0 270)
			(size 0.3048 0.381)
			(layers "B.Cu" "B.Mask" "B.Paste")
			(net "GND")
		)
	)
	(footprint ""
		(layer "B.Cu")
		(at 91.987878 -140.18641 -90)
		(property "Reference" "R8176"
			(at 0 0 90)
			(layer "B.SilkS")
			(hide yes)
			(effects
				(font
					(size 1.27 1.27)
				)
				(justify mirror)
			)
		)
		(property "Value" ""
			(at 0 0 90)
			(layer "B.Fab")
			(effects
				(font
					(size 1.27 1.27)
				)
				(justify mirror)
			)
		)
		(duplicate_pad_numbers_are_jumpers no)
		(fp_line
			(start -0.7874 0.4064)
			(end 0.7874 0.4064)
			(stroke
				(width 0.1524)
				(type default)
			)
			(layer "B.SilkS")
		)
		(fp_line
			(start 0.7874 0.4064)
			(end 0.7874 -0.4064)
			(stroke
				(width 0.1524)
				(type default)
			)
			(layer "B.SilkS")
		)
		(fp_line
			(start -0.7874 -0.4064)
			(end -0.7874 0.4064)
			(stroke
				(width 0.1524)
				(type default)
			)
			(layer "B.SilkS")
		)
		(fp_line
			(start 0.7874 -0.4064)
			(end -0.7874 -0.4064)
			(stroke
				(width 0.1524)
				(type default)
			)
			(layer "B.SilkS")
		)
		(fp_line
			(start -0.67945 0.3048)
			(end -0.120396 0.3048)
			(stroke
				(width 0.1)
				(type default)
			)
			(layer "B.Fab")
		)
		(fp_line
			(start -0.120396 0.3048)
			(end -0.120396 0.2794)
			(stroke
				(width 0.1)
				(type default)
			)
			(layer "B.Fab")
		)
		(fp_line
			(start 0.12065 0.3048)
			(end 0.67945 0.3048)
			(stroke
				(width 0.1)
				(type default)
			)
			(layer "B.Fab")
		)
		(fp_line
			(start 0.67945 0.3048)
			(end 0.67945 -0.305054)
			(stroke
				(width 0.1)
				(type default)
			)
			(layer "B.Fab")
		)
		(fp_line
			(start -0.120396 0.2794)
			(end 0.12065 0.2794)
			(stroke
				(width 0.1)
				(type default)
			)
			(layer "B.Fab")
		)
		(fp_line
			(start 0.12065 0.2794)
			(end 0.12065 0.3048)
			(stroke
				(width 0.1)
				(type default)
			)
			(layer "B.Fab")
		)
		(fp_line
			(start -0.12065 -0.2794)
			(end -0.12065 -0.3048)
			(stroke
				(width 0.1)
				(type default)
			)
			(layer "B.Fab")
		)
		(fp_line
			(start 0.12065 -0.2794)
			(end -0.12065 -0.2794)
			(stroke
				(width 0.1)
				(type default)
			)
			(layer "B.Fab")
		)
		(fp_line
			(start -0.67945 -0.3048)
			(end -0.67945 0.3048)
			(stroke
				(width 0.1)
				(type default)
			)
			(layer "B.Fab")
		)
		(fp_line
			(start -0.12065 -0.3048)
			(end -0.67945 -0.3048)
			(stroke
				(width 0.1)
				(type default)
			)
			(layer "B.Fab")
		)
		(fp_line
			(start 0.12065 -0.305054)
			(end 0.12065 -0.2794)
			(stroke
				(width 0.1)
				(type default)
			)
			(layer "B.Fab")
		)
		(fp_line
			(start 0.67945 -0.305054)
			(end 0.12065 -0.305054)
			(stroke
				(width 0.1)
				(type default)
			)
			(layer "B.Fab")
		)
		(pad "1" smd circle
			(at 0.40005 0 90)
			(size 0 0)
			(layers "B.Cu" "B.Mask" "B.Paste")
			(net "SMB_VR_3V3STBY_SDA")
		)
		(pad "2" smd circle
			(at -0.40005 0 90)
			(size 0 0)
			(layers "B.Cu" "B.Mask" "B.Paste")
			(net "PVDDCR_CPU0_P1_PMSDA_R")
		)
	)
	(footprint ""
		(layer "B.Cu")
		(at 229.993698 -289.533838 -90)
		(property "Reference" "PR6521"
			(at 0 0 90)
			(layer "B.SilkS")
			(hide yes)
			(effects
				(font
					(size 1.27 1.27)
				)
				(justify mirror)
			)
		)
		(property "Value" ""
			(at 0 0 90)
			(layer "B.Fab")
			(effects
				(font
					(size 1.27 1.27)
				)
				(justify mirror)
			)
		)
		(duplicate_pad_numbers_are_jumpers no)
		(fp_line
			(start -0.7874 0.4064)
			(end 0.7874 0.4064)
			(stroke
				(width 0.1524)
				(type default)
			)
			(layer "B.SilkS")
		)
		(fp_line
			(start 0.7874 0.4064)
			(end 0.7874 -0.4064)
			(stroke
				(width 0.1524)
				(type default)
			)
			(layer "B.SilkS")
		)
		(fp_line
			(start -0.7874 -0.4064)
			(end -0.7874 0.4064)
			(stroke
				(width 0.1524)
				(type default)
			)
			(layer "B.SilkS")
		)
		(fp_line
			(start 0.7874 -0.4064)
			(end -0.7874 -0.4064)
			(stroke
				(width 0.1524)
				(type default)
			)
			(layer "B.SilkS")
		)
		(fp_line
			(start -0.67945 0.3048)
			(end -0.120396 0.3048)
			(stroke
				(width 0.1)
				(type default)
			)
			(layer "B.Fab")
		)
		(fp_line
			(start -0.120396 0.3048)
			(end -0.120396 0.2794)
			(stroke
				(width 0.1)
				(type default)
			)
			(layer "B.Fab")
		)
		(fp_line
			(start 0.12065 0.3048)
			(end 0.67945 0.3048)
			(stroke
				(width 0.1)
				(type default)
			)
			(layer "B.Fab")
		)
		(fp_line
			(start 0.67945 0.3048)
			(end 0.67945 -0.305054)
			(stroke
				(width 0.1)
				(type default)
			)
			(layer "B.Fab")
		)
		(fp_line
			(start -0.120396 0.2794)
			(end 0.12065 0.2794)
			(stroke
				(width 0.1)
				(type default)
			)
			(layer "B.Fab")
		)
		(fp_line
			(start 0.12065 0.2794)
			(end 0.12065 0.3048)
			(stroke
				(width 0.1)
				(type default)
			)
			(layer "B.Fab")
		)
		(fp_line
			(start -0.12065 -0.2794)
			(end -0.12065 -0.3048)
			(stroke
				(width 0.1)
				(type default)
			)
			(layer "B.Fab")
		)
		(fp_line
			(start 0.12065 -0.2794)
			(end -0.12065 -0.2794)
			(stroke
				(width 0.1)
				(type default)
			)
			(layer "B.Fab")
		)
		(fp_line
			(start -0.67945 -0.3048)
			(end -0.67945 0.3048)
			(stroke
				(width 0.1)
				(type default)
			)
			(layer "B.Fab")
		)
		(fp_line
			(start -0.12065 -0.3048)
			(end -0.67945 -0.3048)
			(stroke
				(width 0.1)
				(type default)
			)
			(layer "B.Fab")
		)
		(fp_line
			(start 0.12065 -0.305054)
			(end 0.12065 -0.2794)
			(stroke
				(width 0.1)
				(type default)
			)
			(layer "B.Fab")
		)
		(fp_line
			(start 0.67945 -0.305054)
			(end 0.12065 -0.305054)
			(stroke
				(width 0.1)
				(type default)
			)
			(layer "B.Fab")
		)
		(pad "1" smd circle
			(at 0.40005 0 90)
			(size 0 0)
			(layers "B.Cu" "B.Mask" "B.Paste")
			(net "P3V3_AUX")
		)
		(pad "2" smd circle
			(at -0.40005 0 90)
			(size 0 0)
			(layers "B.Cu" "B.Mask" "B.Paste")
			(net "P1V8_RETIMER_CPU1_VCC")
		)
	)
	(footprint ""
		(layer "B.Cu")
		(at 440.40171 -13.627354)
		(property "Reference" "C1235"
			(at 0 0 0)
			(layer "B.SilkS")
			(hide yes)
			(effects
				(font
					(size 1.27 1.27)
				)
				(justify mirror)
			)
		)
		(property "Value" ""
			(at 0 0 0)
			(layer "B.Fab")
			(effects
				(font
					(size 1.27 1.27)
				)
				(justify mirror)
			)
		)
		(duplicate_pad_numbers_are_jumpers no)
		(fp_line
			(start -0.7874 -0.4064)
			(end -0.7874 0.4064)
			(stroke
				(width 0.1524)
				(type default)
			)
			(layer "B.SilkS")
		)
		(fp_line
			(start -0.7874 0.4064)
			(end 0.7874 0.4064)
			(stroke
				(width 0.1524)
				(type default)
			)
			(layer "B.SilkS")
		)
		(fp_line
			(start 0.7874 -0.4064)
			(end -0.7874 -0.4064)
			(stroke
				(width 0.1524)
				(type default)
			)
			(layer "B.SilkS")
		)
		(fp_line
			(start 0.7874 0.4064)
			(end 0.7874 -0.4064)
			(stroke
				(width 0.1524)
				(type default)
			)
			(layer "B.SilkS")
		)
		(fp_line
			(start -0.67945 -0.3048)
			(end -0.67945 0.3048)
			(stroke
				(width 0.1)
				(type default)
			)
			(layer "B.Fab")
		)
		(fp_line
			(start -0.67945 0.3048)
			(end -0.120396 0.3048)
			(stroke
				(width 0.1)
				(type default)
			)
			(layer "B.Fab")
		)
		(fp_line
			(start -0.12065 -0.3048)
			(end -0.67945 -0.3048)
			(stroke
				(width 0.1)
				(type default)
			)
			(layer "B.Fab")
		)
		(fp_line
			(start -0.12065 -0.2794)
			(end -0.12065 -0.3048)
			(stroke
				(width 0.1)
				(type default)
			)
			(layer "B.Fab")
		)
		(fp_line
			(start -0.120396 0.2794)
			(end 0.12065 0.2794)
			(stroke
				(width 0.1)
				(type default)
			)
			(layer "B.Fab")
		)
		(fp_line
			(start -0.120396 0.3048)
			(end -0.120396 0.2794)
			(stroke
				(width 0.1)
				(type default)
			)
			(layer "B.Fab")
		)
		(fp_line
			(start 0.12065 -0.305054)
			(end 0.12065 -0.2794)
			(stroke
				(width 0.1)
				(type default)
			)
			(layer "B.Fab")
		)
		(fp_line
			(start 0.12065 -0.2794)
			(end -0.12065 -0.2794)
			(stroke
				(width 0.1)
				(type default)
			)
			(layer "B.Fab")
		)
		(fp_line
			(start 0.12065 0.2794)
			(end 0.12065 0.3048)
			(stroke
				(width 0.1)
				(type default)
			)
			(layer "B.Fab")
		)
		(fp_line
			(start 0.12065 0.3048)
			(end 0.67945 0.3048)
			(stroke
				(width 0.1)
				(type default)
			)
			(layer "B.Fab")
		)
		(fp_line
			(start 0.67945 -0.305054)
			(end 0.12065 -0.305054)
			(stroke
				(width 0.1)
				(type default)
			)
			(layer "B.Fab")
		)
		(fp_line
			(start 0.67945 0.3048)
			(end 0.67945 -0.305054)
			(stroke
				(width 0.1)
				(type default)
			)
			(layer "B.Fab")
		)
		(pad "1" smd circle
			(at 0.40005 0 180)
			(size 0 0)
			(layers "B.Cu" "B.Mask" "B.Paste")
			(net "P12V_OCP_SFF_R")
		)
		(pad "2" smd circle
			(at -0.40005 0 180)
			(size 0 0)
			(layers "B.Cu" "B.Mask" "B.Paste")
			(net "GND")
		)
	)
	(footprint ""
		(layer "B.Cu")
		(at 380.629922 -148.30171 -90)
		(property "Reference" "PR440"
			(at 0 0 90)
			(layer "B.SilkS")
			(hide yes)
			(effects
				(font
					(size 1.27 1.27)
				)
				(justify mirror)
			)
		)
		(property "Value" ""
			(at 0 0 90)
			(layer "B.Fab")
			(effects
				(font
					(size 1.27 1.27)
				)
				(justify mirror)
			)
		)
		(duplicate_pad_numbers_are_jumpers no)
		(fp_line
			(start -0.7874 0.4064)
			(end 0.7874 0.4064)
			(stroke
				(width 0.1524)
				(type default)
			)
			(layer "B.SilkS")
		)
		(fp_line
			(start 0.7874 0.4064)
			(end 0.7874 -0.4064)
			(stroke
				(width 0.1524)
				(type default)
			)
			(layer "B.SilkS")
		)
		(fp_line
			(start -0.7874 -0.4064)
			(end -0.7874 0.4064)
			(stroke
				(width 0.1524)
				(type default)
			)
			(layer "B.SilkS")
		)
		(fp_line
			(start 0.7874 -0.4064)
			(end -0.7874 -0.4064)
			(stroke
				(width 0.1524)
				(type default)
			)
			(layer "B.SilkS")
		)
		(fp_line
			(start -0.67945 0.3048)
			(end -0.120396 0.3048)
			(stroke
				(width 0.1)
				(type default)
			)
			(layer "B.Fab")
		)
		(fp_line
			(start -0.120396 0.3048)
			(end -0.120396 0.2794)
			(stroke
				(width 0.1)
				(type default)
			)
			(layer "B.Fab")
		)
		(fp_line
			(start 0.12065 0.3048)
			(end 0.67945 0.3048)
			(stroke
				(width 0.1)
				(type default)
			)
			(layer "B.Fab")
		)
		(fp_line
			(start 0.67945 0.3048)
			(end 0.67945 -0.305054)
			(stroke
				(width 0.1)
				(type default)
			)
			(layer "B.Fab")
		)
		(fp_line
			(start -0.120396 0.2794)
			(end 0.12065 0.2794)
			(stroke
				(width 0.1)
				(type default)
			)
			(layer "B.Fab")
		)
		(fp_line
			(start 0.12065 0.2794)
			(end 0.12065 0.3048)
			(stroke
				(width 0.1)
				(type default)
			)
			(layer "B.Fab")
		)
		(fp_line
			(start -0.12065 -0.2794)
			(end -0.12065 -0.3048)
			(stroke
				(width 0.1)
				(type default)
			)
			(layer "B.Fab")
		)
		(fp_line
			(start 0.12065 -0.2794)
			(end -0.12065 -0.2794)
			(stroke
				(width 0.1)
				(type default)
			)
			(layer "B.Fab")
		)
		(fp_line
			(start -0.67945 -0.3048)
			(end -0.67945 0.3048)
			(stroke
				(width 0.1)
				(type default)
			)
			(layer "B.Fab")
		)
		(fp_line
			(start -0.12065 -0.3048)
			(end -0.67945 -0.3048)
			(stroke
				(width 0.1)
				(type default)
			)
			(layer "B.Fab")
		)
		(fp_line
			(start 0.12065 -0.305054)
			(end 0.12065 -0.2794)
			(stroke
				(width 0.1)
				(type default)
			)
			(layer "B.Fab")
		)
		(fp_line
			(start 0.67945 -0.305054)
			(end 0.12065 -0.305054)
			(stroke
				(width 0.1)
				(type default)
			)
			(layer "B.Fab")
		)
		(pad "1" smd circle
			(at 0.40005 0 90)
			(size 0 0)
			(layers "B.Cu" "B.Mask" "B.Paste")
			(net "NC_PVDDCR_CPU0_P0_IMON8")
		)
		(pad "2" smd circle
			(at -0.40005 0 90)
			(size 0 0)
			(layers "B.Cu" "B.Mask" "B.Paste")
			(net "GND")
		)
	)
)
